FILE_TYPE = CONNECTIVITY;
{Allegro Design Entry HDL 16.6-p007 (v16-6-112F) 10/10/2012}
"PAGE_NUMBER" = 60;
0"NC";
1"M_K_DQS_DP<17:0>";
2"M_K_DQS_DN<17:0>";
3"M_K_MA<17:0>";
4"M_K_BA<1:0>";
5"M_K_BG<1:0>";
6"M_K_CKE<3:0>";
7"M_K_CS_N<7:0>";
8"M_K_ODT<3:0>";
9"M_K_DQ<63:0>";
10"M_K_CLK_DN<3:0>";
11"M_K_CLK_DP<3:0>";
12"M_K_ECC<7:0>";
13"M_K_DQ<55>";
14"M_K_ECC<1>";
15"M_K_DQ<41>";
16"M_K_DQ<52>";
17"M_K_ODT<2>";
18"M_K_DQ<34>";
19"M_K_DQ<32>";
20"M_K_C<2>";
21"M_K_ECC<0>";
22"M_K_ECC<2>";
23"M_K_ECC<3>";
24"M_K_ECC<4>";
25"M_K_ECC<5>";
26"M_K_ECC<6>";
27"M_K_ECC<7>";
28"M_K_DQ<0>";
29"M_K_DQ<1>";
30"M_K_DQ<2>";
31"M_K_DQ<3>";
32"M_K_DQ<4>";
33"M_K_DQ<5>";
34"M_K_DQ<6>";
35"M_K_DQ<7>";
36"M_K_DQ<8>";
37"M_K_DQ<9>";
38"M_K_DQ<10>";
39"M_K_CLK_DP<0>";
40"M_K_CLK_DP<1>";
41"M_K_CLK_DP<2>";
42"M_K_CLK_DP<3>";
43"M_K_CLK_DN<0>";
44"M_K_CLK_DN<1>";
45"M_K_CLK_DN<2>";
46"M_K_CLK_DN<3>";
47"M_K_DQ<11>";
48"M_K_DQ<12>";
49"M_K_DQ<13>";
50"M_K_DQ<14>";
51"M_K_DQ<15>";
52"M_K_DQ<16>";
53"M_K_DQ<17>";
54"M_K_DQ<18>";
55"M_K_DQ<19>";
56"M_K_DQ<20>";
57"M_K_DQ<21>";
58"M_K_DQ<22>";
59"M_K_DQ<23>";
60"M_K_DQ<24>";
61"M_K_DQ<25>";
62"M_K_DQ<26>";
63"M_K_DQ<27>";
64"M_K_DQ<28>";
65"M_K_DQ<29>";
66"M_K_DQ<30>";
67"M_K_DQ<31>";
68"M_K_DQ<33>";
69"M_K_DQ<35>";
70"M_K_DQ<36>";
71"M_K_DQ<37>";
72"M_K_DQ<38>";
73"M_K_DQ<39>";
74"M_K_DQ<40>";
75"M_K_DQ<42>";
76"M_K_DQ<43>";
77"M_K_DQ<44>";
78"M_K_DQ<45>";
79"M_K_DQ<46>";
80"M_K_DQ<47>";
81"M_K_DQ<48>";
82"M_K_DQ<49>";
83"M_K_DQ<50>";
84"M_K_DQ<51>";
85"M_K_DQ<53>";
86"M_K_DQ<54>";
87"M_K_DQ<56>";
88"M_K_DQ<57>";
89"M_K_DQ<58>";
90"M_K_DQ<59>";
91"M_K_DQ<60>";
92"M_K_DQ<61>";
93"M_K_DQ<62>";
94"M_K_DQ<63>";
95"M_K_ODT<0>";
96"M_K_ODT<1>";
97"M_K_ODT<3>";
98"M_K_MA<0>";
99"M_K_MA<1>";
100"M_K_MA<2>";
101"M_K_CS_N<0>";
102"M_K_CS_N<1>";
103"M_K_CS_N<2>";
104"M_K_CS_N<3>";
105"M_K_CS_N<4>";
106"M_K_CS_N<5>";
107"M_K_CS_N<6>";
108"M_K_CS_N<7>";
109"M_K_CKE<0>";
110"M_K_CKE<1>";
111"M_K_CKE<2>";
112"M_K_CKE<3>";
113"M_K_BG<0>";
114"M_K_BG<1>";
115"M_K_BA<0>";
116"M_K_BA<1>";
117"M_K_PAR";
118"M_K_ALERT_N";
119"M_K_ACT_N";
120"M_K_MA<3>";
121"M_K_MA<4>";
122"M_K_MA<5>";
123"M_K_MA<6>";
124"M_K_MA<7>";
125"M_K_MA<8>";
126"M_K_MA<9>";
127"M_K_MA<10>";
128"M_K_MA<11>";
129"M_K_MA<12>";
130"M_K_MA<13>";
131"M_K_MA<14>";
132"M_K_MA<15>";
133"M_K_MA<16>";
134"M_K_MA<17>";
135"M_K_DQS_DP<0>";
136"M_K_DQS_DP<1>";
137"M_K_DQS_DP<2>";
138"M_K_DQS_DP<3>";
139"M_K_DQS_DP<4>";
140"M_K_DQS_DP<5>";
141"M_K_DQS_DN<0>";
142"M_K_DQS_DN<1>";
143"M_K_DQS_DN<2>";
144"M_K_DQS_DN<3>";
145"M_K_DQS_DN<4>";
146"M_K_DQS_DN<5>";
147"M_K_DQS_DN<6>";
148"M_K_DQS_DN<7>";
149"M_K_DQS_DN<8>";
150"M_K_DQS_DN<9>";
151"M_K_DQS_DN<10>";
152"M_K_DQS_DN<11>";
153"M_K_DQS_DN<12>";
154"M_K_DQS_DN<13>";
155"M_K_DQS_DN<14>";
156"M_K_DQS_DN<15>";
157"M_K_DQS_DN<16>";
158"M_K_DQS_DN<17>";
159"M_K_DQS_DP<6>";
160"M_K_DQS_DP<7>";
161"M_K_DQS_DP<8>";
162"M_K_DQS_DP<9>";
163"M_K_DQS_DP<10>";
164"M_K_DQS_DP<11>";
165"M_K_DQS_DP<12>";
166"M_K_DQS_DP<13>";
167"M_K_DQS_DP<14>";
168"M_K_DQS_DP<15>";
169"M_K_DQS_DP<16>";
170"M_K_DQS_DP<17>";
%"TAP"
"6","(-5575,825)","0","mstr_standard","I10";
;
CDS_LIB"mstr_standard"
BODY_TYPE"PLUMBING"
HDL_TAP"TRUE";
"B \NAC \NWC"11;
"S \NAC"
BN"0"39;
%"TAP"
"6","(-2850,1575)","2","mstr_standard","I100";
;
CDS_LIB"mstr_standard"
BODY_TYPE"PLUMBING"
HDL_TAP"TRUE";
"B \NAC \NWC"8;
"S \NAC"
BN"3"97;
%"TAP"
"6","(-2850,1525)","2","mstr_standard","I101";
;
CDS_LIB"mstr_standard"
BODY_TYPE"PLUMBING"
HDL_TAP"TRUE";
"B \NAC \NWC"8;
"S \NAC"
BN"2"17;
%"TAP"
"6","(-2850,1475)","2","mstr_standard","I102";
;
CDS_LIB"mstr_standard"
BODY_TYPE"PLUMBING"
HDL_TAP"TRUE";
"B \NAC \NWC"8;
"S \NAC"
BN"1"96;
%"TAP"
"6","(-2850,1675)","2","mstr_standard","I103";
;
CDS_LIB"mstr_standard"
BODY_TYPE"PLUMBING"
HDL_TAP"TRUE";
"B \NAC \NWC"6;
"S \NAC"
BN"0"109;
%"TAP"
"6","(-2850,1725)","2","mstr_standard","I104";
;
CDS_LIB"mstr_standard"
BODY_TYPE"PLUMBING"
HDL_TAP"TRUE";
"B \NAC \NWC"6;
"S \NAC"
BN"1"110;
%"TAP"
"6","(-2850,1775)","2","mstr_standard","I105";
;
CDS_LIB"mstr_standard"
BODY_TYPE"PLUMBING"
HDL_TAP"TRUE";
"B \NAC \NWC"6;
"S \NAC"
BN"2"111;
%"TAP"
"6","(-2850,1825)","2","mstr_standard","I106";
;
CDS_LIB"mstr_standard"
BODY_TYPE"PLUMBING"
HDL_TAP"TRUE";
"B \NAC \NWC"6;
"S \NAC"
BN"3"112;
%"TAP"
"6","(-2850,1925)","2","mstr_standard","I107";
;
CDS_LIB"mstr_standard"
BODY_TYPE"PLUMBING"
HDL_TAP"TRUE";
"B \NAC \NWC"3;
"S \NAC"
BN"0"98;
%"TAP"
"6","(-2850,1975)","2","mstr_standard","I108";
;
CDS_LIB"mstr_standard"
BODY_TYPE"PLUMBING"
HDL_TAP"TRUE";
"B \NAC \NWC"3;
"S \NAC"
BN"1"99;
%"TAP"
"6","(-2850,2075)","2","mstr_standard","I109";
;
CDS_LIB"mstr_standard"
BODY_TYPE"PLUMBING"
HDL_TAP"TRUE";
"B \NAC \NWC"3;
"S \NAC"
BN"3"120;
%"TAP"
"6","(-5575,925)","0","mstr_standard","I11";
;
CDS_LIB"mstr_standard"
BODY_TYPE"PLUMBING"
HDL_TAP"TRUE";
"B \NAC \NWC"11;
"S \NAC"
BN"2"41;
%"TAP"
"6","(-2850,2025)","2","mstr_standard","I110";
;
CDS_LIB"mstr_standard"
BODY_TYPE"PLUMBING"
HDL_TAP"TRUE";
"B \NAC \NWC"3;
"S \NAC"
BN"2"100;
%"TAP"
"6","(-2850,2125)","2","mstr_standard","I111";
;
CDS_LIB"mstr_standard"
BODY_TYPE"PLUMBING"
HDL_TAP"TRUE";
"B \NAC \NWC"3;
"S \NAC"
BN"4"121;
%"TAP"
"6","(-2850,2175)","2","mstr_standard","I112";
;
CDS_LIB"mstr_standard"
BODY_TYPE"PLUMBING"
HDL_TAP"TRUE";
"B \NAC \NWC"3;
"S \NAC"
BN"5"122;
%"TAP"
"6","(-2850,2225)","2","mstr_standard","I113";
;
CDS_LIB"mstr_standard"
BODY_TYPE"PLUMBING"
HDL_TAP"TRUE";
"B \NAC \NWC"3;
"S \NAC"
BN"6"123;
%"TAP"
"6","(-2850,2325)","2","mstr_standard","I114";
;
CDS_LIB"mstr_standard"
BODY_TYPE"PLUMBING"
HDL_TAP"TRUE";
"B \NAC \NWC"3;
"S \NAC"
BN"8"125;
%"TAP"
"6","(-2850,2275)","2","mstr_standard","I115";
;
CDS_LIB"mstr_standard"
BODY_TYPE"PLUMBING"
HDL_TAP"TRUE";
"B \NAC \NWC"3;
"S \NAC"
BN"7"124;
%"TAP"
"6","(-2850,2475)","2","mstr_standard","I116";
;
CDS_LIB"mstr_standard"
BODY_TYPE"PLUMBING"
HDL_TAP"TRUE";
"B \NAC \NWC"3;
"S \NAC"
BN"11"128;
%"TAP"
"6","(-2850,2425)","2","mstr_standard","I117";
;
CDS_LIB"mstr_standard"
BODY_TYPE"PLUMBING"
HDL_TAP"TRUE";
"B \NAC \NWC"3;
"S \NAC"
BN"10"127;
%"TAP"
"6","(-2850,2375)","2","mstr_standard","I118";
;
CDS_LIB"mstr_standard"
BODY_TYPE"PLUMBING"
HDL_TAP"TRUE";
"B \NAC \NWC"3;
"S \NAC"
BN"9"126;
%"TAP"
"6","(-2850,2525)","2","mstr_standard","I119";
;
CDS_LIB"mstr_standard"
BODY_TYPE"PLUMBING"
HDL_TAP"TRUE";
"B \NAC \NWC"3;
"S \NAC"
BN"12"129;
%"TAP"
"6","(-5575,975)","0","mstr_standard","I12";
;
CDS_LIB"mstr_standard"
BODY_TYPE"PLUMBING"
HDL_TAP"TRUE";
"B \NAC \NWC"11;
"S \NAC"
BN"3"42;
%"TAP"
"6","(-2850,2575)","2","mstr_standard","I120";
;
CDS_LIB"mstr_standard"
BODY_TYPE"PLUMBING"
HDL_TAP"TRUE";
"B \NAC \NWC"3;
"S \NAC"
BN"13"130;
%"TAP"
"6","(-2850,2625)","2","mstr_standard","I121";
;
CDS_LIB"mstr_standard"
BODY_TYPE"PLUMBING"
HDL_TAP"TRUE";
"B \NAC \NWC"3;
"S \NAC"
BN"14"131;
%"TAP"
"6","(-2850,2675)","2","mstr_standard","I122";
;
CDS_LIB"mstr_standard"
BODY_TYPE"PLUMBING"
HDL_TAP"TRUE";
"B \NAC \NWC"3;
"S \NAC"
BN"15"132;
%"TAP"
"6","(-2850,2725)","2","mstr_standard","I123";
;
CDS_LIB"mstr_standard"
BODY_TYPE"PLUMBING"
HDL_TAP"TRUE";
"B \NAC \NWC"3;
"S \NAC"
BN"16"133;
%"TAP"
"6","(-2850,2775)","2","mstr_standard","I124";
;
CDS_LIB"mstr_standard"
BODY_TYPE"PLUMBING"
HDL_TAP"TRUE";
"B \NAC \NWC"3;
"S \NAC"
BN"17"134;
%"TAP"
"6","(-2850,2925)","2","mstr_standard","I125";
;
CDS_LIB"mstr_standard"
BODY_TYPE"PLUMBING"
HDL_TAP"TRUE";
"B \NAC \NWC"2;
"S \NAC"
BN"1"142;
%"TAP"
"6","(-2850,2975)","2","mstr_standard","I126";
;
CDS_LIB"mstr_standard"
BODY_TYPE"PLUMBING"
HDL_TAP"TRUE";
"B \NAC \NWC"2;
"S \NAC"
BN"2"143;
%"TAP"
"6","(-2850,2875)","2","mstr_standard","I127";
;
CDS_LIB"mstr_standard"
BODY_TYPE"PLUMBING"
HDL_TAP"TRUE";
"B \NAC \NWC"2;
"S \NAC"
BN"0"141;
%"TAP"
"6","(-2850,3075)","2","mstr_standard","I128";
;
CDS_LIB"mstr_standard"
BODY_TYPE"PLUMBING"
HDL_TAP"TRUE";
"B \NAC \NWC"2;
"S \NAC"
BN"4"145;
%"TAP"
"6","(-2850,3025)","2","mstr_standard","I129";
;
CDS_LIB"mstr_standard"
BODY_TYPE"PLUMBING"
HDL_TAP"TRUE";
"B \NAC \NWC"2;
"S \NAC"
BN"3"144;
%"TAP"
"6","(-5575,1075)","0","mstr_standard","I13";
;
CDS_LIB"mstr_standard"
BODY_TYPE"PLUMBING"
HDL_TAP"TRUE";
"B \NAC \NWC"12;
"S \NAC"
BN"0"21;
%"TAP"
"6","(-2850,3125)","2","mstr_standard","I130";
;
CDS_LIB"mstr_standard"
BODY_TYPE"PLUMBING"
HDL_TAP"TRUE";
"B \NAC \NWC"2;
"S \NAC"
BN"5"146;
%"TAP"
"6","(-2850,3175)","2","mstr_standard","I131";
;
CDS_LIB"mstr_standard"
BODY_TYPE"PLUMBING"
HDL_TAP"TRUE";
"B \NAC \NWC"2;
"S \NAC"
BN"6"147;
%"TAP"
"6","(-2850,3225)","2","mstr_standard","I132";
;
CDS_LIB"mstr_standard"
BODY_TYPE"PLUMBING"
HDL_TAP"TRUE";
"B \NAC \NWC"2;
"S \NAC"
BN"7"148;
%"TAP"
"6","(-2850,3275)","2","mstr_standard","I133";
;
CDS_LIB"mstr_standard"
BODY_TYPE"PLUMBING"
HDL_TAP"TRUE";
"B \NAC \NWC"2;
"S \NAC"
BN"8"149;
%"TAP"
"6","(-2850,3325)","2","mstr_standard","I134";
;
CDS_LIB"mstr_standard"
BODY_TYPE"PLUMBING"
HDL_TAP"TRUE";
"B \NAC \NWC"2;
"S \NAC"
BN"9"150;
%"TAP"
"6","(-2850,3375)","2","mstr_standard","I135";
;
CDS_LIB"mstr_standard"
BODY_TYPE"PLUMBING"
HDL_TAP"TRUE";
"B \NAC \NWC"2;
"S \NAC"
BN"10"151;
%"TAP"
"6","(-2850,3475)","2","mstr_standard","I136";
;
CDS_LIB"mstr_standard"
BODY_TYPE"PLUMBING"
HDL_TAP"TRUE";
"B \NAC \NWC"2;
"S \NAC"
BN"12"153;
%"TAP"
"6","(-2850,3425)","2","mstr_standard","I137";
;
CDS_LIB"mstr_standard"
BODY_TYPE"PLUMBING"
HDL_TAP"TRUE";
"B \NAC \NWC"2;
"S \NAC"
BN"11"152;
%"TAP"
"6","(-2850,3625)","2","mstr_standard","I138";
;
CDS_LIB"mstr_standard"
BODY_TYPE"PLUMBING"
HDL_TAP"TRUE";
"B \NAC \NWC"2;
"S \NAC"
BN"15"156;
%"TAP"
"6","(-2850,3575)","2","mstr_standard","I139";
;
CDS_LIB"mstr_standard"
BODY_TYPE"PLUMBING"
HDL_TAP"TRUE";
"B \NAC \NWC"2;
"S \NAC"
BN"14"155;
%"TAP"
"6","(-5575,1125)","0","mstr_standard","I14";
;
CDS_LIB"mstr_standard"
BODY_TYPE"PLUMBING"
HDL_TAP"TRUE";
"B \NAC \NWC"12;
"S \NAC"
BN"1"14;
%"TAP"
"6","(-2850,3525)","2","mstr_standard","I140";
;
CDS_LIB"mstr_standard"
BODY_TYPE"PLUMBING"
HDL_TAP"TRUE";
"B \NAC \NWC"2;
"S \NAC"
BN"13"154;
%"TAP"
"6","(-2850,3675)","2","mstr_standard","I141";
;
CDS_LIB"mstr_standard"
BODY_TYPE"PLUMBING"
HDL_TAP"TRUE";
"B \NAC \NWC"2;
"S \NAC"
BN"16"157;
%"TAP"
"6","(-2850,3725)","2","mstr_standard","I142";
;
CDS_LIB"mstr_standard"
BODY_TYPE"PLUMBING"
HDL_TAP"TRUE";
"B \NAC \NWC"2;
"S \NAC"
BN"17"158;
%"TAP"
"6","(-2850,3825)","2","mstr_standard","I143";
;
CDS_LIB"mstr_standard"
BODY_TYPE"PLUMBING"
HDL_TAP"TRUE";
"B \NAC \NWC"1;
"S \NAC"
BN"0"135;
%"TAP"
"6","(-2850,3875)","2","mstr_standard","I144";
;
CDS_LIB"mstr_standard"
BODY_TYPE"PLUMBING"
HDL_TAP"TRUE";
"B \NAC \NWC"1;
"S \NAC"
BN"1"136;
%"TAP"
"6","(-2850,3925)","2","mstr_standard","I145";
;
CDS_LIB"mstr_standard"
BODY_TYPE"PLUMBING"
HDL_TAP"TRUE";
"B \NAC \NWC"1;
"S \NAC"
BN"2"137;
%"TAP"
"6","(-2850,3975)","2","mstr_standard","I146";
;
CDS_LIB"mstr_standard"
BODY_TYPE"PLUMBING"
HDL_TAP"TRUE";
"B \NAC \NWC"1;
"S \NAC"
BN"3"138;
%"TAP"
"6","(-5575,1175)","0","mstr_standard","I15";
;
CDS_LIB"mstr_standard"
BODY_TYPE"PLUMBING"
HDL_TAP"TRUE";
"B \NAC \NWC"12;
"S \NAC"
BN"2"22;
%"TAP"
"6","(-2850,4025)","2","mstr_standard","I157";
;
CDS_LIB"mstr_standard"
BODY_TYPE"PLUMBING"
HDL_TAP"TRUE";
"B \NAC \NWC"1;
"S \NAC"
BN"4"139;
%"TAP"
"6","(-2850,4125)","2","mstr_standard","I158";
;
CDS_LIB"mstr_standard"
BODY_TYPE"PLUMBING"
HDL_TAP"TRUE";
"B \NAC \NWC"1;
"S \NAC"
BN"6"159;
%"TAP"
"6","(-2850,4075)","2","mstr_standard","I159";
;
CDS_LIB"mstr_standard"
BODY_TYPE"PLUMBING"
HDL_TAP"TRUE";
"B \NAC \NWC"1;
"S \NAC"
BN"5"140;
%"TAP"
"6","(-5575,1275)","0","mstr_standard","I16";
;
CDS_LIB"mstr_standard"
BODY_TYPE"PLUMBING"
HDL_TAP"TRUE";
"B \NAC \NWC"12;
"S \NAC"
BN"4"24;
%"TAP"
"6","(-2850,4175)","2","mstr_standard","I160";
;
CDS_LIB"mstr_standard"
BODY_TYPE"PLUMBING"
HDL_TAP"TRUE";
"B \NAC \NWC"1;
"S \NAC"
BN"7"160;
%"TAP"
"6","(-2850,4225)","2","mstr_standard","I161";
;
CDS_LIB"mstr_standard"
BODY_TYPE"PLUMBING"
HDL_TAP"TRUE";
"B \NAC \NWC"1;
"S \NAC"
BN"8"161;
%"TAP"
"6","(-2850,4275)","2","mstr_standard","I162";
;
CDS_LIB"mstr_standard"
BODY_TYPE"PLUMBING"
HDL_TAP"TRUE";
"B \NAC \NWC"1;
"S \NAC"
BN"9"162;
%"TAP"
"6","(-2850,4325)","2","mstr_standard","I163";
;
CDS_LIB"mstr_standard"
BODY_TYPE"PLUMBING"
HDL_TAP"TRUE";
"B \NAC \NWC"1;
"S \NAC"
BN"10"163;
%"TAP"
"6","(-2850,4375)","2","mstr_standard","I164";
;
CDS_LIB"mstr_standard"
BODY_TYPE"PLUMBING"
HDL_TAP"TRUE";
"B \NAC \NWC"1;
"S \NAC"
BN"11"164;
%"TAP"
"6","(-2850,4525)","2","mstr_standard","I165";
;
CDS_LIB"mstr_standard"
BODY_TYPE"PLUMBING"
HDL_TAP"TRUE";
"B \NAC \NWC"1;
"S \NAC"
BN"14"167;
%"TAP"
"6","(-2850,4475)","2","mstr_standard","I166";
;
CDS_LIB"mstr_standard"
BODY_TYPE"PLUMBING"
HDL_TAP"TRUE";
"B \NAC \NWC"1;
"S \NAC"
BN"13"166;
%"TAP"
"6","(-2850,4425)","2","mstr_standard","I167";
;
CDS_LIB"mstr_standard"
BODY_TYPE"PLUMBING"
HDL_TAP"TRUE";
"B \NAC \NWC"1;
"S \NAC"
BN"12"165;
%"TAP"
"6","(-2850,4575)","2","mstr_standard","I168";
;
CDS_LIB"mstr_standard"
BODY_TYPE"PLUMBING"
HDL_TAP"TRUE";
"B \NAC \NWC"1;
"S \NAC"
BN"15"168;
%"TAP"
"6","(-2850,4625)","2","mstr_standard","I169";
;
CDS_LIB"mstr_standard"
BODY_TYPE"PLUMBING"
HDL_TAP"TRUE";
"B \NAC \NWC"1;
"S \NAC"
BN"16"169;
%"TAP"
"6","(-5575,1225)","0","mstr_standard","I17";
;
CDS_LIB"mstr_standard"
BODY_TYPE"PLUMBING"
HDL_TAP"TRUE";
"B \NAC \NWC"12;
"S \NAC"
BN"3"23;
%"TAP"
"6","(-2850,4675)","2","mstr_standard","I170";
;
CDS_LIB"mstr_standard"
BODY_TYPE"PLUMBING"
HDL_TAP"TRUE";
"B \NAC \NWC"1;
"S \NAC"
BN"17"170;
%"SKX_EXT_B"
"6","(-4175,2575)","0","chpset_lib","I172";
;
CDS_SEC"6"
LOCATION"U2D1"
PART_NUMBER"TBD"
MATERIAL"IC"
PACK_TYPE"BGA1"
SEC_TYPE"BGA1"
CDS_LIB"chpset_lib"
SEC"6"
CDS_LOCATION"U2D1";
"DDR3_PAR"
$PN"ED53"117;
"DDR3_ODT<0>"
$PN"EE50"95;
"DDR3_ODT<1>"
$PN"EE48"96;
"DDR3_ODT<2>"
$PN"EA50"17;
"DDR3_ODT<3>"
$PN"EA48"97;
"DDR3_MA<0>"
$PN"EB53"98;
"DDR3_MA<1>"
$PN"ED57"99;
"DDR3_MA<2>"
$PN"EE58"100;
"DDR3_MA<3>"
$PN"EB57"120;
"DDR3_MA<4>"
$PN"ED59"121;
"DDR3_MA<5>"
$PN"EA58"122;
"DDR3_MA<6>"
$PN"EE60"123;
"DDR3_MA<7>"
$PN"EA60"124;
"DDR3_MA<8>"
$PN"EB59"125;
"DDR3_MA<9>"
$PN"EF61"126;
"DDR3_MA<10>"
$PN"DW54"127;
"DDR3_MA<11>"
$PN"EB61"128;
"DDR3_MA<12>"
$PN"DT63"129;
"DDR3_MA<13>"
$PN"DW48"130;
"DDR3_MA<14>"
$PN"ED51"131;
"DDR3_MA<15>"
$PN"DV49"132;
"DDR3_MA<16>"
$PN"EA52"133;
"DDR3_MA<17>"
$PN"EA46"134;
"DDR3_ECC<0>"
$PN"DA68"21;
"DDR3_ECC<1>"
$PN"DE68"14;
"DDR3_ECC<2>"
$PN"DB65"22;
"DDR3_ECC<3>"
$PN"DD65"23;
"DDR3_ECC<4>"
$PN"DB69"24;
"DDR3_ECC<5>"
$PN"DD69"25;
"DDR3_ECC<6>"
$PN"DA66"26;
"DDR3_ECC<7>"
$PN"DE66"27;
"DDR3_DQS_DP<0>"
$PN"CV85"135;
"DDR3_DQS_DP<1>"
$PN"DP85"136;
"DDR3_DQS_DP<2>"
$PN"DM81"137;
"DDR3_DQS_DP<3>"
$PN"DT75"138;
"DDR3_DQS_DP<4>"
$PN"EC38"139;
"DDR3_DQS_DP<5>"
$PN"DT35"140;
"DDR3_DQS_DP<6>"
$PN"DT29"159;
"DDR3_DQS_DP<7>"
$PN"DT23"160;
"DDR3_DQS_DP<8>"
$PN"DD67"161;
"DDR3_DQS_DP<9>"
$PN"CP85"162;
"DDR3_DQS_DP<10>"
$PN"DL84"163;
"DDR3_DQS_DP<11>"
$PN"DP79"164;
"DDR3_DQS_DP<12>"
$PN"DM75"165;
"DDR3_DQS_DP<13>"
$PN"DW38"166;
"DDR3_DQS_DP<14>"
$PN"DM35"167;
"DDR3_DQS_DP<15>"
$PN"DP29"168;
"DDR3_DQS_DP<16>"
$PN"DP23"169;
"DDR3_DQS_DP<17>"
$PN"CY67"170;
"DDR3_DQS_DN<0>"
$PN"CU84"141;
"DDR3_DQS_DN<1>"
$PN"DN84"142;
"DDR3_DQS_DN<2>"
$PN"DL82"143;
"DDR3_DQS_DN<3>"
$PN"DV75"144;
"DDR3_DQS_DN<4>"
$PN"EE38"145;
"DDR3_DQS_DN<5>"
$PN"DV35"146;
"DDR3_DQS_DN<6>"
$PN"DV29"147;
"DDR3_DQS_DN<7>"
$PN"DV23"148;
"DDR3_DQS_DN<8>"
$PN"DF67"149;
"DDR3_DQS_DN<9>"
$PN"CR84"150;
"DDR3_DQS_DN<10>"
$PN"DM85"151;
"DDR3_DQS_DN<11>"
$PN"DN80"152;
"DDR3_DQS_DN<12>"
$PN"DP75"153;
"DDR3_DQS_DN<13>"
$PN"EA38"154;
"DDR3_DQS_DN<14>"
$PN"DP35"155;
"DDR3_DQS_DN<15>"
$PN"DM29"156;
"DDR3_DQS_DN<16>"
$PN"DM23"157;
"DDR3_DQS_DN<17>"
$PN"DB67"158;
"DDR3_DQ<0>"
$PN"CN84"28;
"DDR3_DQ<1>"
$PN"CN86"29;
"DDR3_DQ<2>"
$PN"DA86"30;
"DDR3_DQ<3>"
$PN"DA84"31;
"DDR3_DQ<4>"
$PN"CL84"32;
"DDR3_DQ<5>"
$PN"CL86"33;
"DDR3_DQ<6>"
$PN"CW86"34;
"DDR3_DQ<7>"
$PN"CW84"35;
"DDR3_DQ<8>"
$PN"DG84"36;
"DDR3_DQ<9>"
$PN"DH85"37;
"DDR3_DQ<10>"
$PN"DV83"38;
"DDR3_DQ<11>"
$PN"DY83"47;
"DDR3_DQ<12>"
$PN"DD85"48;
"DDR3_DQ<13>"
$PN"DE84"49;
"DDR3_DQ<14>"
$PN"DR84"50;
"DDR3_DQ<15>"
$PN"DV85"51;
"DDR3_DQ<16>"
$PN"DM79"52;
"DDR3_DQ<17>"
$PN"DK81"53;
"DDR3_DQ<18>"
$PN"DT81"54;
"DDR3_DQ<19>"
$PN"DR82"55;
"DDR3_DQ<20>"
$PN"DK79"56;
"DDR3_DQ<21>"
$PN"DJ80"57;
"DDR3_DQ<22>"
$PN"DR80"58;
"DDR3_DQ<23>"
$PN"DN82"59;
"DDR3_DQ<24>"
$PN"DN76"60;
"DDR3_DQ<25>"
$PN"DU76"61;
"DDR3_DQ<26>"
$PN"DP73"62;
"DDR3_DQ<27>"
$PN"DT73"63;
"DDR3_DQ<28>"
$PN"DP77"64;
"DDR3_DQ<29>"
$PN"DT77"65;
"DDR3_DQ<30>"
$PN"DN74"66;
"DDR3_DQ<31>"
$PN"DU74"67;
"DDR3_DQ<32>"
$PN"EC40"19;
"DDR3_DQ<33>"
$PN"ED39"68;
"DDR3_DQ<34>"
$PN"EA36"18;
"DDR3_DQ<35>"
$PN"EC36"69;
"DDR3_DQ<36>"
$PN"DY39"70;
"DDR3_DQ<37>"
$PN"EA40"71;
"DDR3_DQ<38>"
$PN"DY37"72;
"DDR3_DQ<39>"
$PN"ED37"73;
"DDR3_DQ<40>"
$PN"DN36"74;
"DDR3_DQ<41>"
$PN"DU36"15;
"DDR3_DQ<42>"
$PN"DP33"75;
"DDR3_DQ<43>"
$PN"DT33"76;
"DDR3_DQ<44>"
$PN"DP37"77;
"DDR3_DQ<45>"
$PN"DT37"78;
"DDR3_DQ<46>"
$PN"DN34"79;
"DDR3_DQ<47>"
$PN"DU34"80;
"DDR3_DQ<48>"
$PN"DN30"81;
"DDR3_DQ<49>"
$PN"DU30"82;
"DDR3_DQ<50>"
$PN"DP27"83;
"DDR3_DQ<51>"
$PN"DT27"84;
"DDR3_DQ<52>"
$PN"DP31"16;
"DDR3_DQ<53>"
$PN"DT31"85;
"DDR3_DQ<54>"
$PN"DN28"86;
"DDR3_DQ<55>"
$PN"DU28"13;
"DDR3_DQ<56>"
$PN"DN24"87;
"DDR3_DQ<57>"
$PN"DU24"88;
"DDR3_DQ<58>"
$PN"DY21"89;
"DDR3_DQ<59>"
$PN"EB21"90;
"DDR3_DQ<60>"
$PN"DP25"91;
"DDR3_DQ<61>"
$PN"DT25"92;
"DDR3_DQ<62>"
$PN"EC22"93;
"DDR3_DQ<63>"
$PN"DW22"94;
"DDR3_CS_N<0>"
$PN"EF51"101;
"DDR3_CS_N<1>"
$PN"ED49"102;
"DDR3_CS_N<2>"
$PN"ED47"103;
"DDR3_CS_N<3>"
$PN"EB47"104;
"DDR3_CS_N<4>"
$PN"EB51"105;
"DDR3_CS_N<5>"
$PN"EB49"106;
"DDR3_CS_N<6>"
$PN"DV45"107;
"DDR3_CS_N<7>"
$PN"EB45"108;
"DDR3_CLK_DP<0>"
$PN"EB55"39;
"DDR3_CLK_DP<1>"
$PN"EE54"40;
"DDR3_CLK_DP<2>"
$PN"EA56"41;
"DDR3_CLK_DP<3>"
$PN"EE56"42;
"DDR3_CLK_DN<0>"
$PN"ED55"43;
"DDR3_CLK_DN<1>"
$PN"EF55"44;
"DDR3_CLK_DN<2>"
$PN"DW56"45;
"DDR3_CLK_DN<3>"
$PN"EF57"46;
"DDR3_CKE<0>"
$PN"EE62"109;
"DDR3_CKE<1>"
$PN"EF63"110;
"DDR3_CKE<2>"
$PN"EA62"111;
"DDR3_CKE<3>"
$PN"EB63"112;
"DDR3_CID<2>"
$PN"DV47"20;
"DDR3_BG<0>"
$PN"ED61"113;
"DDR3_BG<1>"
$PN"DW62"114;
"DDR3_BA<0>"
$PN"EE52"115;
"DDR3_BA<1>"
$PN"EA54"116;
"DDR3_ALERT_N"
$PN"ED63"118;
"DDR3_ACT_N"
$PN"DW60"119;
%"TAP"
"6","(-5575,1325)","0","mstr_standard","I18";
;
CDS_LIB"mstr_standard"
BODY_TYPE"PLUMBING"
HDL_TAP"TRUE";
"B \NAC \NWC"12;
"S \NAC"
BN"5"25;
%"TAP"
"6","(-5575,1375)","0","mstr_standard","I19";
;
CDS_LIB"mstr_standard"
BODY_TYPE"PLUMBING"
HDL_TAP"TRUE";
"B \NAC \NWC"12;
"S \NAC"
BN"6"26;
%"TAP"
"6","(-5575,1425)","0","mstr_standard","I20";
;
CDS_LIB"mstr_standard"
BODY_TYPE"PLUMBING"
HDL_TAP"TRUE";
"B \NAC \NWC"12;
"S \NAC"
BN"7"27;
%"TAP"
"6","(-5575,1525)","0","mstr_standard","I21";
;
CDS_LIB"mstr_standard"
BODY_TYPE"PLUMBING"
HDL_TAP"TRUE";
"B \NAC \NWC"9;
"S \NAC"
BN"0"28;
%"TAP"
"6","(-5575,1575)","0","mstr_standard","I22";
;
CDS_LIB"mstr_standard"
BODY_TYPE"PLUMBING"
HDL_TAP"TRUE";
"B \NAC \NWC"9;
"S \NAC"
BN"1"29;
%"TAP"
"6","(-5575,1625)","0","mstr_standard","I23";
;
CDS_LIB"mstr_standard"
BODY_TYPE"PLUMBING"
HDL_TAP"TRUE";
"B \NAC \NWC"9;
"S \NAC"
BN"2"30;
%"TAP"
"6","(-5575,1675)","0","mstr_standard","I24";
;
CDS_LIB"mstr_standard"
BODY_TYPE"PLUMBING"
HDL_TAP"TRUE";
"B \NAC \NWC"9;
"S \NAC"
BN"3"31;
%"TAP"
"6","(-5575,1725)","0","mstr_standard","I25";
;
CDS_LIB"mstr_standard"
BODY_TYPE"PLUMBING"
HDL_TAP"TRUE";
"B \NAC \NWC"9;
"S \NAC"
BN"4"32;
%"TAP"
"6","(-5575,1775)","0","mstr_standard","I26";
;
CDS_LIB"mstr_standard"
BODY_TYPE"PLUMBING"
HDL_TAP"TRUE";
"B \NAC \NWC"9;
"S \NAC"
BN"5"33;
%"TAP"
"6","(-5575,1825)","0","mstr_standard","I27";
;
CDS_LIB"mstr_standard"
BODY_TYPE"PLUMBING"
HDL_TAP"TRUE";
"B \NAC \NWC"9;
"S \NAC"
BN"6"34;
%"TAP"
"6","(-5575,1925)","0","mstr_standard","I28";
;
CDS_LIB"mstr_standard"
BODY_TYPE"PLUMBING"
HDL_TAP"TRUE";
"B \NAC \NWC"9;
"S \NAC"
BN"8"36;
%"TAP"
"6","(-5575,1875)","0","mstr_standard","I29";
;
CDS_LIB"mstr_standard"
BODY_TYPE"PLUMBING"
HDL_TAP"TRUE";
"B \NAC \NWC"9;
"S \NAC"
BN"7"35;
%"TAP"
"6","(-5575,1975)","0","mstr_standard","I31";
;
CDS_LIB"mstr_standard"
BODY_TYPE"PLUMBING"
HDL_TAP"TRUE";
"B \NAC \NWC"9;
"S \NAC"
BN"9"37;
%"TAP"
"6","(-5575,2025)","0","mstr_standard","I32";
;
CDS_LIB"mstr_standard"
BODY_TYPE"PLUMBING"
HDL_TAP"TRUE";
"B \NAC \NWC"9;
"S \NAC"
BN"10"38;
%"TAP"
"6","(-5575,2075)","0","mstr_standard","I33";
;
CDS_LIB"mstr_standard"
BODY_TYPE"PLUMBING"
HDL_TAP"TRUE";
"B \NAC \NWC"9;
"S \NAC"
BN"11"47;
%"TAP"
"6","(-5575,2125)","0","mstr_standard","I34";
;
CDS_LIB"mstr_standard"
BODY_TYPE"PLUMBING"
HDL_TAP"TRUE";
"B \NAC \NWC"9;
"S \NAC"
BN"12"48;
%"TAP"
"6","(-5575,2175)","0","mstr_standard","I35";
;
CDS_LIB"mstr_standard"
BODY_TYPE"PLUMBING"
HDL_TAP"TRUE";
"B \NAC \NWC"9;
"S \NAC"
BN"13"49;
%"TAP"
"6","(-5575,2225)","0","mstr_standard","I36";
;
CDS_LIB"mstr_standard"
BODY_TYPE"PLUMBING"
HDL_TAP"TRUE";
"B \NAC \NWC"9;
"S \NAC"
BN"14"50;
%"TAP"
"6","(-5575,2275)","0","mstr_standard","I37";
;
CDS_LIB"mstr_standard"
BODY_TYPE"PLUMBING"
HDL_TAP"TRUE";
"B \NAC \NWC"9;
"S \NAC"
BN"15"51;
%"TAP"
"6","(-5575,2325)","0","mstr_standard","I38";
;
CDS_LIB"mstr_standard"
BODY_TYPE"PLUMBING"
HDL_TAP"TRUE";
"B \NAC \NWC"9;
"S \NAC"
BN"16"52;
%"TAP"
"6","(-5575,2375)","0","mstr_standard","I39";
;
CDS_LIB"mstr_standard"
BODY_TYPE"PLUMBING"
HDL_TAP"TRUE";
"B \NAC \NWC"9;
"S \NAC"
BN"17"53;
%"TAP"
"6","(-5575,2425)","0","mstr_standard","I40";
;
CDS_LIB"mstr_standard"
BODY_TYPE"PLUMBING"
HDL_TAP"TRUE";
"B \NAC \NWC"9;
"S \NAC"
BN"18"54;
%"TAP"
"6","(-5575,2475)","0","mstr_standard","I41";
;
CDS_LIB"mstr_standard"
BODY_TYPE"PLUMBING"
HDL_TAP"TRUE";
"B \NAC \NWC"9;
"S \NAC"
BN"19"55;
%"TAP"
"6","(-5575,2525)","0","mstr_standard","I42";
;
CDS_LIB"mstr_standard"
BODY_TYPE"PLUMBING"
HDL_TAP"TRUE";
"B \NAC \NWC"9;
"S \NAC"
BN"20"56;
%"TAP"
"6","(-5575,2575)","0","mstr_standard","I43";
;
CDS_LIB"mstr_standard"
BODY_TYPE"PLUMBING"
HDL_TAP"TRUE";
"B \NAC \NWC"9;
"S \NAC"
BN"21"57;
%"TAP"
"6","(-5575,2625)","0","mstr_standard","I44";
;
CDS_LIB"mstr_standard"
BODY_TYPE"PLUMBING"
HDL_TAP"TRUE";
"B \NAC \NWC"9;
"S \NAC"
BN"22"58;
%"TAP"
"6","(-5575,2675)","0","mstr_standard","I45";
;
CDS_LIB"mstr_standard"
BODY_TYPE"PLUMBING"
HDL_TAP"TRUE";
"B \NAC \NWC"9;
"S \NAC"
BN"23"59;
%"TAP"
"6","(-5575,2725)","0","mstr_standard","I46";
;
CDS_LIB"mstr_standard"
BODY_TYPE"PLUMBING"
HDL_TAP"TRUE";
"B \NAC \NWC"9;
"S \NAC"
BN"24"60;
%"TAP"
"6","(-5575,2825)","0","mstr_standard","I47";
;
CDS_LIB"mstr_standard"
BODY_TYPE"PLUMBING"
HDL_TAP"TRUE";
"B \NAC \NWC"9;
"S \NAC"
BN"26"62;
%"TAP"
"6","(-5575,2775)","0","mstr_standard","I48";
;
CDS_LIB"mstr_standard"
BODY_TYPE"PLUMBING"
HDL_TAP"TRUE";
"B \NAC \NWC"9;
"S \NAC"
BN"25"61;
%"TAP"
"6","(-5575,2875)","0","mstr_standard","I49";
;
CDS_LIB"mstr_standard"
BODY_TYPE"PLUMBING"
HDL_TAP"TRUE";
"B \NAC \NWC"9;
"S \NAC"
BN"27"63;
%"TAP"
"6","(-5575,625)","0","mstr_standard","I5";
;
CDS_LIB"mstr_standard"
BODY_TYPE"PLUMBING"
HDL_TAP"TRUE";
"B \NAC \NWC"10;
"S \NAC"
BN"0"43;
%"TAP"
"6","(-5575,2925)","0","mstr_standard","I50";
;
CDS_LIB"mstr_standard"
BODY_TYPE"PLUMBING"
HDL_TAP"TRUE";
"B \NAC \NWC"9;
"S \NAC"
BN"28"64;
%"TAP"
"6","(-5575,2975)","0","mstr_standard","I51";
;
CDS_LIB"mstr_standard"
BODY_TYPE"PLUMBING"
HDL_TAP"TRUE";
"B \NAC \NWC"9;
"S \NAC"
BN"29"65;
%"TAP"
"6","(-5575,3075)","0","mstr_standard","I52";
;
CDS_LIB"mstr_standard"
BODY_TYPE"PLUMBING"
HDL_TAP"TRUE";
"B \NAC \NWC"9;
"S \NAC"
BN"31"67;
%"TAP"
"6","(-5575,3025)","0","mstr_standard","I53";
;
CDS_LIB"mstr_standard"
BODY_TYPE"PLUMBING"
HDL_TAP"TRUE";
"B \NAC \NWC"9;
"S \NAC"
BN"30"66;
%"TAP"
"6","(-5575,3125)","0","mstr_standard","I54";
;
CDS_LIB"mstr_standard"
BODY_TYPE"PLUMBING"
HDL_TAP"TRUE";
"B \NAC \NWC"9;
"S \NAC"
BN"32"19;
%"TAP"
"6","(-5575,3175)","0","mstr_standard","I55";
;
CDS_LIB"mstr_standard"
BODY_TYPE"PLUMBING"
HDL_TAP"TRUE";
"B \NAC \NWC"9;
"S \NAC"
BN"33"68;
%"TAP"
"6","(-5575,3225)","0","mstr_standard","I56";
;
CDS_LIB"mstr_standard"
BODY_TYPE"PLUMBING"
HDL_TAP"TRUE";
"B \NAC \NWC"9;
"S \NAC"
BN"34"18;
%"TAP"
"6","(-5575,3325)","0","mstr_standard","I57";
;
CDS_LIB"mstr_standard"
BODY_TYPE"PLUMBING"
HDL_TAP"TRUE";
"B \NAC \NWC"9;
"S \NAC"
BN"36"70;
%"TAP"
"6","(-5575,3275)","0","mstr_standard","I58";
;
CDS_LIB"mstr_standard"
BODY_TYPE"PLUMBING"
HDL_TAP"TRUE";
"B \NAC \NWC"9;
"S \NAC"
BN"35"69;
%"TAP"
"6","(-5575,3375)","0","mstr_standard","I59";
;
CDS_LIB"mstr_standard"
BODY_TYPE"PLUMBING"
HDL_TAP"TRUE";
"B \NAC \NWC"9;
"S \NAC"
BN"37"71;
%"TAP"
"6","(-5575,675)","0","mstr_standard","I6";
;
CDS_LIB"mstr_standard"
BODY_TYPE"PLUMBING"
HDL_TAP"TRUE";
"B \NAC \NWC"10;
"S \NAC"
BN"1"44;
%"TAP"
"6","(-5575,3425)","0","mstr_standard","I60";
;
CDS_LIB"mstr_standard"
BODY_TYPE"PLUMBING"
HDL_TAP"TRUE";
"B \NAC \NWC"9;
"S \NAC"
BN"38"72;
%"TAP"
"6","(-5575,3475)","0","mstr_standard","I61";
;
CDS_LIB"mstr_standard"
BODY_TYPE"PLUMBING"
HDL_TAP"TRUE";
"B \NAC \NWC"9;
"S \NAC"
BN"39"73;
%"TAP"
"6","(-5575,3525)","0","mstr_standard","I62";
;
CDS_LIB"mstr_standard"
BODY_TYPE"PLUMBING"
HDL_TAP"TRUE";
"B \NAC \NWC"9;
"S \NAC"
BN"40"74;
%"TAP"
"6","(-5575,3575)","0","mstr_standard","I63";
;
CDS_LIB"mstr_standard"
BODY_TYPE"PLUMBING"
HDL_TAP"TRUE";
"B \NAC \NWC"9;
"S \NAC"
BN"41"15;
%"TAP"
"6","(-5575,3625)","0","mstr_standard","I64";
;
CDS_LIB"mstr_standard"
BODY_TYPE"PLUMBING"
HDL_TAP"TRUE";
"B \NAC \NWC"9;
"S \NAC"
BN"42"75;
%"TAP"
"6","(-5575,3675)","0","mstr_standard","I65";
;
CDS_LIB"mstr_standard"
BODY_TYPE"PLUMBING"
HDL_TAP"TRUE";
"B \NAC \NWC"9;
"S \NAC"
BN"43"76;
%"TAP"
"6","(-5575,3725)","0","mstr_standard","I66";
;
CDS_LIB"mstr_standard"
BODY_TYPE"PLUMBING"
HDL_TAP"TRUE";
"B \NAC \NWC"9;
"S \NAC"
BN"44"77;
%"TAP"
"6","(-5575,3775)","0","mstr_standard","I67";
;
CDS_LIB"mstr_standard"
BODY_TYPE"PLUMBING"
HDL_TAP"TRUE";
"B \NAC \NWC"9;
"S \NAC"
BN"45"78;
%"TAP"
"6","(-5575,3825)","0","mstr_standard","I68";
;
CDS_LIB"mstr_standard"
BODY_TYPE"PLUMBING"
HDL_TAP"TRUE";
"B \NAC \NWC"9;
"S \NAC"
BN"46"79;
%"TAP"
"6","(-5575,3875)","0","mstr_standard","I69";
;
CDS_LIB"mstr_standard"
BODY_TYPE"PLUMBING"
HDL_TAP"TRUE";
"B \NAC \NWC"9;
"S \NAC"
BN"47"80;
%"TAP"
"6","(-5575,775)","0","mstr_standard","I7";
;
CDS_LIB"mstr_standard"
BODY_TYPE"PLUMBING"
HDL_TAP"TRUE";
"B \NAC \NWC"10;
"S \NAC"
BN"3"46;
%"TAP"
"6","(-5575,3925)","0","mstr_standard","I70";
;
CDS_LIB"mstr_standard"
BODY_TYPE"PLUMBING"
HDL_TAP"TRUE";
"B \NAC \NWC"9;
"S \NAC"
BN"48"81;
%"TAP"
"6","(-5575,3975)","0","mstr_standard","I71";
;
CDS_LIB"mstr_standard"
BODY_TYPE"PLUMBING"
HDL_TAP"TRUE";
"B \NAC \NWC"9;
"S \NAC"
BN"49"82;
%"TAP"
"6","(-5575,4025)","0","mstr_standard","I73";
;
CDS_LIB"mstr_standard"
BODY_TYPE"PLUMBING"
HDL_TAP"TRUE";
"B \NAC \NWC"9;
"S \NAC"
BN"50"83;
%"TAP"
"6","(-5575,4075)","0","mstr_standard","I74";
;
CDS_LIB"mstr_standard"
BODY_TYPE"PLUMBING"
HDL_TAP"TRUE";
"B \NAC \NWC"9;
"S \NAC"
BN"51"84;
%"TAP"
"6","(-5575,4125)","0","mstr_standard","I75";
;
CDS_LIB"mstr_standard"
BODY_TYPE"PLUMBING"
HDL_TAP"TRUE";
"B \NAC \NWC"9;
"S \NAC"
BN"52"16;
%"TAP"
"6","(-5575,4175)","0","mstr_standard","I76";
;
CDS_LIB"mstr_standard"
BODY_TYPE"PLUMBING"
HDL_TAP"TRUE";
"B \NAC \NWC"9;
"S \NAC"
BN"53"85;
%"TAP"
"6","(-5575,4225)","0","mstr_standard","I77";
;
CDS_LIB"mstr_standard"
BODY_TYPE"PLUMBING"
HDL_TAP"TRUE";
"B \NAC \NWC"9;
"S \NAC"
BN"54"86;
%"TAP"
"6","(-5575,4275)","0","mstr_standard","I78";
;
CDS_LIB"mstr_standard"
BODY_TYPE"PLUMBING"
HDL_TAP"TRUE";
"B \NAC \NWC"9;
"S \NAC"
BN"55"13;
%"TAP"
"6","(-5575,4325)","0","mstr_standard","I79";
;
CDS_LIB"mstr_standard"
BODY_TYPE"PLUMBING"
HDL_TAP"TRUE";
"B \NAC \NWC"9;
"S \NAC"
BN"56"87;
%"TAP"
"6","(-5575,725)","0","mstr_standard","I8";
;
CDS_LIB"mstr_standard"
BODY_TYPE"PLUMBING"
HDL_TAP"TRUE";
"B \NAC \NWC"10;
"S \NAC"
BN"2"45;
%"TAP"
"6","(-5575,4375)","0","mstr_standard","I80";
;
CDS_LIB"mstr_standard"
BODY_TYPE"PLUMBING"
HDL_TAP"TRUE";
"B \NAC \NWC"9;
"S \NAC"
BN"57"88;
%"TAP"
"6","(-5575,4425)","0","mstr_standard","I81";
;
CDS_LIB"mstr_standard"
BODY_TYPE"PLUMBING"
HDL_TAP"TRUE";
"B \NAC \NWC"9;
"S \NAC"
BN"58"89;
%"TAP"
"6","(-5575,4475)","0","mstr_standard","I82";
;
CDS_LIB"mstr_standard"
BODY_TYPE"PLUMBING"
HDL_TAP"TRUE";
"B \NAC \NWC"9;
"S \NAC"
BN"59"90;
%"TAP"
"6","(-5575,4525)","0","mstr_standard","I83";
;
CDS_LIB"mstr_standard"
BODY_TYPE"PLUMBING"
HDL_TAP"TRUE";
"B \NAC \NWC"9;
"S \NAC"
BN"60"91;
%"TAP"
"6","(-5575,4575)","0","mstr_standard","I84";
;
CDS_LIB"mstr_standard"
BODY_TYPE"PLUMBING"
HDL_TAP"TRUE";
"B \NAC \NWC"9;
"S \NAC"
BN"61"92;
%"TAP"
"6","(-5575,4625)","0","mstr_standard","I85";
;
CDS_LIB"mstr_standard"
BODY_TYPE"PLUMBING"
HDL_TAP"TRUE";
"B \NAC \NWC"9;
"S \NAC"
BN"62"93;
%"TAP"
"6","(-5575,4675)","0","mstr_standard","I86";
;
CDS_LIB"mstr_standard"
BODY_TYPE"PLUMBING"
HDL_TAP"TRUE";
"B \NAC \NWC"9;
"S \NAC"
BN"63"94;
%"TAP"
"6","(-2850,775)","2","mstr_standard","I87";
;
CDS_LIB"mstr_standard"
BODY_TYPE"PLUMBING"
HDL_TAP"TRUE";
"B \NAC \NWC"4;
"S \NAC"
BN"1"116;
%"TAP"
"6","(-2850,725)","2","mstr_standard","I88";
;
CDS_LIB"mstr_standard"
BODY_TYPE"PLUMBING"
HDL_TAP"TRUE";
"B \NAC \NWC"4;
"S \NAC"
BN"0"115;
%"TAP"
"6","(-2850,825)","2","mstr_standard","I89";
;
CDS_LIB"mstr_standard"
BODY_TYPE"PLUMBING"
HDL_TAP"TRUE";
"B \NAC \NWC"5;
"S \NAC"
BN"0"113;
%"TAP"
"6","(-5575,875)","0","mstr_standard","I9";
;
CDS_LIB"mstr_standard"
BODY_TYPE"PLUMBING"
HDL_TAP"TRUE";
"B \NAC \NWC"11;
"S \NAC"
BN"1"40;
%"TAP"
"6","(-2850,875)","2","mstr_standard","I90";
;
CDS_LIB"mstr_standard"
BODY_TYPE"PLUMBING"
HDL_TAP"TRUE";
"B \NAC \NWC"5;
"S \NAC"
BN"1"114;
%"TAP"
"6","(-2850,1075)","2","mstr_standard","I91";
;
CDS_LIB"mstr_standard"
BODY_TYPE"PLUMBING"
HDL_TAP"TRUE";
"B \NAC \NWC"7;
"S \NAC"
BN"2"103;
%"TAP"
"6","(-2850,1025)","2","mstr_standard","I92";
;
CDS_LIB"mstr_standard"
BODY_TYPE"PLUMBING"
HDL_TAP"TRUE";
"B \NAC \NWC"7;
"S \NAC"
BN"1"102;
%"TAP"
"6","(-2850,975)","2","mstr_standard","I93";
;
CDS_LIB"mstr_standard"
BODY_TYPE"PLUMBING"
HDL_TAP"TRUE";
"B \NAC \NWC"7;
"S \NAC"
BN"0"101;
%"TAP"
"6","(-2850,1175)","2","mstr_standard","I94";
;
CDS_LIB"mstr_standard"
BODY_TYPE"PLUMBING"
HDL_TAP"TRUE";
"B \NAC \NWC"7;
"S \NAC"
BN"4"105;
%"TAP"
"6","(-2850,1125)","2","mstr_standard","I95";
;
CDS_LIB"mstr_standard"
BODY_TYPE"PLUMBING"
HDL_TAP"TRUE";
"B \NAC \NWC"7;
"S \NAC"
BN"3"104;
%"TAP"
"6","(-2850,1225)","2","mstr_standard","I96";
;
CDS_LIB"mstr_standard"
BODY_TYPE"PLUMBING"
HDL_TAP"TRUE";
"B \NAC \NWC"7;
"S \NAC"
BN"5"106;
%"TAP"
"6","(-2850,1275)","2","mstr_standard","I97";
;
CDS_LIB"mstr_standard"
BODY_TYPE"PLUMBING"
HDL_TAP"TRUE";
"B \NAC \NWC"7;
"S \NAC"
BN"6"107;
%"TAP"
"6","(-2850,1325)","2","mstr_standard","I98";
;
CDS_LIB"mstr_standard"
BODY_TYPE"PLUMBING"
HDL_TAP"TRUE";
"B \NAC \NWC"7;
"S \NAC"
BN"7"108;
%"TAP"
"6","(-2850,1425)","2","mstr_standard","I99";
;
CDS_LIB"mstr_standard"
BODY_TYPE"PLUMBING"
HDL_TAP"TRUE";
"B \NAC \NWC"8;
"S \NAC"
BN"0"95;
END.
